# T6G (Grand Teton) — schematic netlist excerpt (pin names and nets, part order shuffled) for the footprints in the layout excerpt that follows; sources: Cadence DE-HDL packaged netlist, KiCad conversion of 04192023_DAF0TMB3IC0_F0TG_MB_C_brd_V02_OCP.brd

C6073  Q_CAP  0.001UF 50V 10% X7R  pkg C0402  page 177 : A = P1V2_AUX ; B = GND
C429  Q_CAP  10UF 6.3V 20% X6S  pkg C0402  page 345 : A = P0V9_CPU1_RT2_2A ; B = GND

(kicad_pcb
	(version 20260206)
	(generator "pcbnew")
	(generator_version "10.0")
	(general
		(thickness 1.6)
		(legacy_teardrops no)
	)
	(paper "A4")
	(title_block
		(title "04192023_DAF0TMB3IC0_F0TG_MB_C_brd_V02_OCP.brd")
		(comment 1 "Grand Teton / footprints 7321-7322 of 8354")
	)
	(layers
		(0 "F.Cu" signal "TOP")
		(4 "In1.Cu" signal "GND")
		(6 "In2.Cu" signal "IN1")
		(8 "In3.Cu" signal "GND1")
		(10 "In4.Cu" signal "IN2")
		(12 "In5.Cu" signal "GND2")
		(14 "In6.Cu" signal "IN3")
		(16 "In7.Cu" signal "GND3")
		(18 "In8.Cu" signal "VCC")
		(20 "In9.Cu" signal "VCC1")
		(22 "In10.Cu" signal "GND4")
		(24 "In11.Cu" signal "IN4")
		(26 "In12.Cu" signal "GND5")
		(28 "In13.Cu" signal "IN5")
		(30 "In14.Cu" signal "GND6")
		(32 "In15.Cu" signal "IN6")
		(34 "In16.Cu" signal "GND7")
		(2 "B.Cu" signal "BOTTOM")
		(9 "F.Adhes" user "F.Adhesive")
		(11 "B.Adhes" user "B.Adhesive")
		(13 "F.Paste" user "Package Geometry/Pastemask Top")
		(15 "B.Paste" user "Package Geometry/Pastemask Bottom")
		(5 "F.SilkS" user "Ref Des/Silkscreen Top")
		(7 "B.SilkS" user "Ref Des/Silkscreen Bottom")
		(1 "F.Mask" user "Board Geometry/Soldermask Top")
		(3 "B.Mask" user "Board Geometry/Soldermask Bottom")
		(17 "Dwgs.User" user "User.Drawings")
		(19 "Cmts.User" user "User.Comments")
		(21 "Eco1.User" user "User.Eco1")
		(23 "Eco2.User" user "User.Eco2")
		(25 "Edge.Cuts" user "Board Geometry/Outline")
		(27 "Margin" user)
		(31 "F.CrtYd" user "Package Geometry/Place Bound Top")
		(29 "B.CrtYd" user "Package Geometry/Place Bound Bottom")
		(35 "F.Fab" user "Ref Des/Assembly Top")
		(33 "B.Fab" user "Ref Des/Assembly Bottom")
	)
	(footprint ""
		(layer "B.Cu")
		(at 150.618952 -390.560052 90)
		(property "Reference" "C429"
			(at 0 0 90)
			(layer "B.SilkS")
			(hide yes)
			(effects
				(font
					(size 1.27 1.27)
				)
				(justify mirror)
			)
		)
		(property "Value" ""
			(at 0 0 90)
			(layer "B.Fab")
			(effects
				(font
					(size 1.27 1.27)
				)
				(justify mirror)
			)
		)
		(duplicate_pad_numbers_are_jumpers no)
		(fp_line
			(start 0.7874 -0.4064)
			(end -0.7874 -0.4064)
			(stroke
				(width 0.1524)
				(type default)
			)
			(layer "B.SilkS")
		)
		(fp_line
			(start -0.7874 -0.4064)
			(end -0.7874 0.4064)
			(stroke
				(width 0.1524)
				(type default)
			)
			(layer "B.SilkS")
		)
		(fp_line
			(start 0.7874 0.4064)
			(end 0.7874 -0.4064)
			(stroke
				(width 0.1524)
				(type default)
			)
			(layer "B.SilkS")
		)
		(fp_line
			(start -0.7874 0.4064)
			(end 0.7874 0.4064)
			(stroke
				(width 0.1524)
				(type default)
			)
			(layer "B.SilkS")
		)
		(fp_line
			(start 0.67945 -0.305054)
			(end 0.12065 -0.305054)
			(stroke
				(width 0.1)
				(type default)
			)
			(layer "B.Fab")
		)
		(fp_line
			(start 0.12065 -0.305054)
			(end 0.12065 -0.2794)
			(stroke
				(width 0.1)
				(type default)
			)
			(layer "B.Fab")
		)
		(fp_line
			(start -0.12065 -0.3048)
			(end -0.67945 -0.3048)
			(stroke
				(width 0.1)
				(type default)
			)
			(layer "B.Fab")
		)
		(fp_line
			(start -0.67945 -0.3048)
			(end -0.67945 0.3048)
			(stroke
				(width 0.1)
				(type default)
			)
			(layer "B.Fab")
		)
		(fp_line
			(start 0.12065 -0.2794)
			(end -0.12065 -0.2794)
			(stroke
				(width 0.1)
				(type default)
			)
			(layer "B.Fab")
		)
		(fp_line
			(start -0.12065 -0.2794)
			(end -0.12065 -0.3048)
			(stroke
				(width 0.1)
				(type default)
			)
			(layer "B.Fab")
		)
		(fp_line
			(start 0.12065 0.2794)
			(end 0.12065 0.3048)
			(stroke
				(width 0.1)
				(type default)
			)
			(layer "B.Fab")
		)
		(fp_line
			(start -0.120396 0.2794)
			(end 0.12065 0.2794)
			(stroke
				(width 0.1)
				(type default)
			)
			(layer "B.Fab")
		)
		(fp_line
			(start 0.67945 0.3048)
			(end 0.67945 -0.305054)
			(stroke
				(width 0.1)
				(type default)
			)
			(layer "B.Fab")
		)
		(fp_line
			(start 0.12065 0.3048)
			(end 0.67945 0.3048)
			(stroke
				(width 0.1)
				(type default)
			)
			(layer "B.Fab")
		)
		(fp_line
			(start -0.120396 0.3048)
			(end -0.120396 0.2794)
			(stroke
				(width 0.1)
				(type default)
			)
			(layer "B.Fab")
		)
		(fp_line
			(start -0.67945 0.3048)
			(end -0.120396 0.3048)
			(stroke
				(width 0.1)
				(type default)
			)
			(layer "B.Fab")
		)
		(pad "1" smd circle
			(at 0.40005 0 270)
			(size 0 0)
			(layers "B.Cu" "B.Mask" "B.Paste")
			(net "P0V9_CPU1_RT2_2A")
		)
		(pad "2" smd circle
			(at -0.40005 0 270)
			(size 0 0)
			(layers "B.Cu" "B.Mask" "B.Paste")
			(net "GND")
		)
	)
	(footprint ""
		(layer "B.Cu")
		(at 126.375668 -36.46043)
		(property "Reference" "C6073"
			(at 0 0 0)
			(layer "B.SilkS")
			(hide yes)
			(effects
				(font
					(size 1.27 1.27)
				)
				(justify mirror)
			)
		)
		(property "Value" ""
			(at 0 0 0)
			(layer "B.Fab")
			(effects
				(font
					(size 1.27 1.27)
				)
				(justify mirror)
			)
		)
		(duplicate_pad_numbers_are_jumpers no)
		(fp_line
			(start -0.7874 -0.4064)
			(end -0.7874 0.4064)
			(stroke
				(width 0.1524)
				(type default)
			)
			(layer "B.SilkS")
		)
		(fp_line
			(start -0.7874 0.4064)
			(end 0.7874 0.4064)
			(stroke
				(width 0.1524)
				(type default)
			)
			(layer "B.SilkS")
		)
		(fp_line
			(start 0.7874 -0.4064)
			(end -0.7874 -0.4064)
			(stroke
				(width 0.1524)
				(type default)
			)
			(layer "B.SilkS")
		)
		(fp_line
			(start 0.7874 0.4064)
			(end 0.7874 -0.4064)
			(stroke
				(width 0.1524)
				(type default)
			)
			(layer "B.SilkS")
		)
		(fp_line
			(start -0.67945 -0.3048)
			(end -0.67945 0.3048)
			(stroke
				(width 0.1)
				(type default)
			)
			(layer "B.Fab")
		)
		(fp_line
			(start -0.67945 0.3048)
			(end -0.120396 0.3048)
			(stroke
				(width 0.1)
				(type default)
			)
			(layer "B.Fab")
		)
		(fp_line
			(start -0.12065 -0.3048)
			(end -0.67945 -0.3048)
			(stroke
				(width 0.1)
				(type default)
			)
			(layer "B.Fab")
		)
		(fp_line
			(start -0.12065 -0.2794)
			(end -0.12065 -0.3048)
			(stroke
				(width 0.1)
				(type default)
			)
			(layer "B.Fab")
		)
		(fp_line
			(start -0.120396 0.2794)
			(end 0.12065 0.2794)
			(stroke
				(width 0.1)
				(type default)
			)
			(layer "B.Fab")
		)
		(fp_line
			(start -0.120396 0.3048)
			(end -0.120396 0.2794)
			(stroke
				(width 0.1)
				(type default)
			)
			(layer "B.Fab")
		)
		(fp_line
			(start 0.12065 -0.305054)
			(end 0.12065 -0.2794)
			(stroke
				(width 0.1)
				(type default)
			)
			(layer "B.Fab")
		)
		(fp_line
			(start 0.12065 -0.2794)
			(end -0.12065 -0.2794)
			(stroke
				(width 0.1)
				(type default)
			)
			(layer "B.Fab")
		)
		(fp_line
			(start 0.12065 0.2794)
			(end 0.12065 0.3048)
			(stroke
				(width 0.1)
				(type default)
			)
			(layer "B.Fab")
		)
		(fp_line
			(start 0.12065 0.3048)
			(end 0.67945 0.3048)
			(stroke
				(width 0.1)
				(type default)
			)
			(layer "B.Fab")
		)
		(fp_line
			(start 0.67945 -0.305054)
			(end 0.12065 -0.305054)
			(stroke
				(width 0.1)
				(type default)
			)
			(layer "B.Fab")
		)
		(fp_line
			(start 0.67945 0.3048)
			(end 0.67945 -0.305054)
			(stroke
				(width 0.1)
				(type default)
			)
			(layer "B.Fab")
		)
		(pad "1" smd circle
			(at 0.40005 0 180)
			(size 0 0)
			(layers "B.Cu" "B.Mask" "B.Paste")
			(net "P1V2_AUX")
		)
		(pad "2" smd circle
			(at -0.40005 0 180)
			(size 0 0)
			(layers "B.Cu" "B.Mask" "B.Paste")
			(net "GND")
		)
	)
)
